# S9S_MB_2U (Grand Teton) — schematic netlist excerpt (pin names and nets, part order shuffled) for the footprints in the layout excerpt that follows; sources: Cadence DE-HDL packaged netlist, KiCad conversion of 03242023_DA0F0TMBIJ0_F0T_Motherboard_J_brd_V01_OCP.brd

PC2645  Q_CAPP  330UF 2.5V +10/-35% SPCAP  pkg SMLF  page 271 : A = PVCCFA_EHV_FIVRA_CPU0 ; B = GND
C525  Q_CAP  47UF 4V 20% X6S  pkg C0805  page 76 : A = PVCCINFAON_CPU0 ; B = GND
R689  Q_RES  0 5% CHIP  pkg 0402LF  page 229 : A = I3C_SPD_DDREFGH_CPU0_SCL ; B = I3C_SPD_DDREFGH_CPU0_R_SCL

(kicad_pcb
	(version 20260206)
	(generator "pcbnew")
	(generator_version "10.0")
	(general
		(thickness 1.6)
		(legacy_teardrops no)
	)
	(paper "A4")
	(title_block
		(title "03242023_DA0F0TMBIJ0_F0T_Motherboard_J_brd_V01_OCP.brd")
		(comment 1 "Grand Teton / footprints 5052-5054 of 6105")
	)
	(layers
		(0 "F.Cu" signal "TOP")
		(4 "In1.Cu" signal "GND")
		(6 "In2.Cu" signal "IN1")
		(8 "In3.Cu" signal "GND1")
		(10 "In4.Cu" signal "IN2")
		(12 "In5.Cu" signal "GND2")
		(14 "In6.Cu" signal "IN3")
		(16 "In7.Cu" signal "GND3")
		(18 "In8.Cu" signal "VCC")
		(20 "In9.Cu" signal "VCC1")
		(22 "In10.Cu" signal "GND4")
		(24 "In11.Cu" signal "IN4")
		(26 "In12.Cu" signal "GND5")
		(28 "In13.Cu" signal "IN5")
		(30 "In14.Cu" signal "GND6")
		(32 "In15.Cu" signal "IN6")
		(34 "In16.Cu" signal "GND7")
		(2 "B.Cu" signal "BOTTOM")
		(9 "F.Adhes" user "F.Adhesive")
		(11 "B.Adhes" user "B.Adhesive")
		(13 "F.Paste" user "Package Geometry/Pastemask Top")
		(15 "B.Paste" user "Package Geometry/Pastemask Bottom")
		(5 "F.SilkS" user "Ref Des/Silkscreen Top")
		(7 "B.SilkS" user "Ref Des/Silkscreen Bottom")
		(1 "F.Mask" user "Board Geometry/Soldermask Top")
		(3 "B.Mask" user "Board Geometry/Soldermask Bottom")
		(17 "Dwgs.User" user "User.Drawings")
		(19 "Cmts.User" user "User.Comments")
		(21 "Eco1.User" user "User.Eco1")
		(23 "Eco2.User" user "User.Eco2")
		(25 "Edge.Cuts" user "Board Geometry/Outline")
		(27 "Margin" user)
		(31 "F.CrtYd" user "Package Geometry/Place Bound Top")
		(29 "B.CrtYd" user "Package Geometry/Place Bound Bottom")
		(35 "F.Fab" user "Ref Des/Assembly Top")
		(33 "B.Fab" user "Ref Des/Assembly Bottom")
	)
	(footprint ""
		(layer "B.Cu")
		(at 416.121342 -354.903786 -90)
		(property "Reference" "PC2645"
			(at 0 0 90)
			(layer "B.SilkS")
			(hide yes)
			(effects
				(font
					(size 1.27 1.27)
				)
				(justify mirror)
			)
		)
		(property "Value" ""
			(at 0 0 90)
			(layer "B.Fab")
			(effects
				(font
					(size 1.27 1.27)
				)
				(justify mirror)
			)
		)
		(duplicate_pad_numbers_are_jumpers no)
		(fp_line
			(start -4.533392 2.249932)
			(end 4.533392 2.249932)
			(stroke
				(width 0.1524)
				(type default)
			)
			(layer "B.SilkS")
		)
		(fp_line
			(start 4.533392 2.249932)
			(end 4.533392 -2.249932)
			(stroke
				(width 0.1524)
				(type default)
			)
			(layer "B.SilkS")
		)
		(fp_line
			(start -4.533392 -2.249932)
			(end -4.533392 2.249932)
			(stroke
				(width 0.1524)
				(type default)
			)
			(layer "B.SilkS")
		)
		(fp_line
			(start 4.533392 -2.249932)
			(end -4.533392 -2.249932)
			(stroke
				(width 0.1524)
				(type default)
			)
			(layer "B.SilkS")
		)
		(fp_rect
			(start 5.39242 2.326132)
			(end 4.533392 -2.326132)
			(stroke
				(width 0)
				(type default)
			)
			(fill yes)
			(layer "B.SilkS")
		)
		(fp_line
			(start -3.750056 2.249932)
			(end 3.750056 2.249932)
			(stroke
				(width 0.1)
				(type default)
			)
			(layer "B.Fab")
		)
		(fp_line
			(start 3.750056 2.249932)
			(end 3.750056 -2.249932)
			(stroke
				(width 0.1)
				(type default)
			)
			(layer "B.Fab")
		)
		(fp_line
			(start -3.750056 -2.249932)
			(end -3.750056 2.249932)
			(stroke
				(width 0.1)
				(type default)
			)
			(layer "B.Fab")
		)
		(fp_line
			(start 3.750056 -2.249932)
			(end -3.750056 -2.249932)
			(stroke
				(width 0.1)
				(type default)
			)
			(layer "B.Fab")
		)
		(fp_text user "-"
			(at -4.598162 1.848612 270)
			(unlocked yes)
			(layer "B.SilkS")
			(effects
				(font
					(size 1.905 1.4224)
					(thickness 0.1524)
				)
				(justify left mirror)
			)
		)
		(fp_text user "+"
			(at 6.322314 0.786384 180)
			(unlocked yes)
			(layer "B.SilkS")
			(effects
				(font
					(size 1.905 1.4224)
					(thickness 0.1524)
				)
				(justify left mirror)
			)
		)
		(fp_text user "+"
			(at 6.322314 0.786384 180)
			(unlocked yes)
			(layer "B.Fab")
			(effects
				(font
					(size 1.905 1.4224)
					(thickness 0.1524)
				)
				(justify left mirror)
			)
		)
		(fp_text user "-"
			(at -4.8514 -0.14605 270)
			(unlocked yes)
			(layer "B.Fab")
			(effects
				(font
					(size 1.905 1.4224)
					(thickness 0.1524)
				)
				(justify left mirror)
			)
		)
		(pad "1" smd rect
			(at 3.199892 0 90)
			(size 2.413 2.8194)
			(layers "B.Cu" "B.Mask" "B.Paste")
			(net "PVCCFA_EHV_FIVRA_CPU0")
		)
		(pad "2" smd rect
			(at -3.199892 0 90)
			(size 2.413 2.8194)
			(layers "B.Cu" "B.Mask" "B.Paste")
			(net "GND")
		)
	)
	(footprint ""
		(layer "B.Cu")
		(at 366.09782 -212.049614)
		(property "Reference" "C525"
			(at 0 0 0)
			(layer "B.SilkS")
			(hide yes)
			(effects
				(font
					(size 1.27 1.27)
				)
				(justify mirror)
			)
		)
		(property "Value" ""
			(at 0 0 0)
			(layer "B.Fab")
			(effects
				(font
					(size 1.27 1.27)
				)
				(justify mirror)
			)
		)
		(duplicate_pad_numbers_are_jumpers no)
		(fp_line
			(start -1.524 -0.762)
			(end -1.524 0.762)
			(stroke
				(width 0.1524)
				(type default)
			)
			(layer "B.SilkS")
		)
		(fp_line
			(start -1.524 0.762)
			(end 1.524 0.762)
			(stroke
				(width 0.1524)
				(type default)
			)
			(layer "B.SilkS")
		)
		(fp_line
			(start 1.524 -0.762)
			(end -1.524 -0.762)
			(stroke
				(width 0.1524)
				(type default)
			)
			(layer "B.SilkS")
		)
		(fp_line
			(start 1.524 0.762)
			(end 1.524 -0.762)
			(stroke
				(width 0.1524)
				(type default)
			)
			(layer "B.SilkS")
		)
		(fp_line
			(start -1.1049 -0.724916)
			(end 1.1049 -0.724916)
			(stroke
				(width 0.1)
				(type default)
			)
			(layer "B.Fab")
		)
		(fp_line
			(start -1.1049 0.724916)
			(end -1.1049 -0.724916)
			(stroke
				(width 0.1)
				(type default)
			)
			(layer "B.Fab")
		)
		(fp_line
			(start 1.1049 -0.724916)
			(end 1.1049 0.724916)
			(stroke
				(width 0.1)
				(type default)
			)
			(layer "B.Fab")
		)
		(fp_line
			(start 1.1049 0.724916)
			(end -1.1049 0.724916)
			(stroke
				(width 0.1)
				(type default)
			)
			(layer "B.Fab")
		)
		(pad "1" smd rect
			(at 0.889 0)
			(size 1.016 1.27)
			(layers "B.Cu" "B.Mask" "B.Paste")
			(net "PVCCINFAON_CPU0")
		)
		(pad "2" smd rect
			(at -0.889 0)
			(size 1.016 1.27)
			(layers "B.Cu" "B.Mask" "B.Paste")
			(net "GND")
		)
	)
	(footprint ""
		(layer "B.Cu")
		(at 376.618754 -190.703708 90)
		(property "Reference" "R689"
			(at 0 0 90)
			(layer "B.SilkS")
			(hide yes)
			(effects
				(font
					(size 1.27 1.27)
				)
				(justify mirror)
			)
		)
		(property "Value" ""
			(at 0 0 90)
			(layer "B.Fab")
			(effects
				(font
					(size 1.27 1.27)
				)
				(justify mirror)
			)
		)
		(duplicate_pad_numbers_are_jumpers no)
		(fp_line
			(start 0.7874 -0.4064)
			(end -0.7874 -0.4064)
			(stroke
				(width 0.1524)
				(type default)
			)
			(layer "B.SilkS")
		)
		(fp_line
			(start -0.7874 -0.4064)
			(end -0.7874 0.4064)
			(stroke
				(width 0.1524)
				(type default)
			)
			(layer "B.SilkS")
		)
		(fp_line
			(start 0.7874 0.4064)
			(end 0.7874 -0.4064)
			(stroke
				(width 0.1524)
				(type default)
			)
			(layer "B.SilkS")
		)
		(fp_line
			(start -0.7874 0.4064)
			(end 0.7874 0.4064)
			(stroke
				(width 0.1524)
				(type default)
			)
			(layer "B.SilkS")
		)
		(fp_line
			(start 0.67945 -0.305054)
			(end 0.12065 -0.305054)
			(stroke
				(width 0.1)
				(type default)
			)
			(layer "B.Fab")
		)
		(fp_line
			(start 0.12065 -0.305054)
			(end 0.12065 -0.2794)
			(stroke
				(width 0.1)
				(type default)
			)
			(layer "B.Fab")
		)
		(fp_line
			(start -0.12065 -0.3048)
			(end -0.67945 -0.3048)
			(stroke
				(width 0.1)
				(type default)
			)
			(layer "B.Fab")
		)
		(fp_line
			(start -0.67945 -0.3048)
			(end -0.67945 0.3048)
			(stroke
				(width 0.1)
				(type default)
			)
			(layer "B.Fab")
		)
		(fp_line
			(start 0.12065 -0.2794)
			(end -0.12065 -0.2794)
			(stroke
				(width 0.1)
				(type default)
			)
			(layer "B.Fab")
		)
		(fp_line
			(start -0.12065 -0.2794)
			(end -0.12065 -0.3048)
			(stroke
				(width 0.1)
				(type default)
			)
			(layer "B.Fab")
		)
		(fp_line
			(start 0.12065 0.2794)
			(end 0.12065 0.3048)
			(stroke
				(width 0.1)
				(type default)
			)
			(layer "B.Fab")
		)
		(fp_line
			(start -0.120396 0.2794)
			(end 0.12065 0.2794)
			(stroke
				(width 0.1)
				(type default)
			)
			(layer "B.Fab")
		)
		(fp_line
			(start 0.67945 0.3048)
			(end 0.67945 -0.305054)
			(stroke
				(width 0.1)
				(type default)
			)
			(layer "B.Fab")
		)
		(fp_line
			(start 0.12065 0.3048)
			(end 0.67945 0.3048)
			(stroke
				(width 0.1)
				(type default)
			)
			(layer "B.Fab")
		)
		(fp_line
			(start -0.120396 0.3048)
			(end -0.120396 0.2794)
			(stroke
				(width 0.1)
				(type default)
			)
			(layer "B.Fab")
		)
		(fp_line
			(start -0.67945 0.3048)
			(end -0.120396 0.3048)
			(stroke
				(width 0.1)
				(type default)
			)
			(layer "B.Fab")
		)
		(pad "1" smd circle
			(at 0.40005 0 270)
			(size 0 0)
			(layers "B.Cu" "B.Mask" "B.Paste")
			(net "I3C_SPD_DDREFGH_CPU0_SCL")
		)
		(pad "2" smd circle
			(at -0.40005 0 270)
			(size 0 0)
			(layers "B.Cu" "B.Mask" "B.Paste")
			(net "I3C_SPD_DDREFGH_CPU0_R_SCL")
		)
	)
)
